# TIMECARD (Time Appliance Project (Time Card)) — schematic netlist excerpt (pin names and nets, part order shuffled) for the footprints in the layout excerpt that follows; sources: Cadence DE-HDL packaged netlist, KiCad conversion of R4006-B0001-02_R01.brd

C180  CAPACITOR  22UF 10V 20%  pkg SMC_0805R_H057  page 30 : \1\ = XP3R3V ; \2\ = SG
R247  RESISTOR  10KOHM 1%  pkg SMC_0402R_H016  page 29 : \1\ = VIN_XP1R0V ; \2\ = UNNAMED_523_CAPACITOR_I7_1

(kicad_pcb
	(version 20260206)
	(generator "pcbnew")
	(generator_version "10.0")
	(general
		(thickness 1.6)
		(legacy_teardrops no)
	)
	(paper "A4")
	(title_block
		(title "timecard-production-celestica-r4006 — R4006-B0001-02_R01.brd")
		(comment 1 "Time Appliance Project (Time Card) / footprints 771-772 of 1113")
	)
	(layers
		(0 "F.Cu" signal "TOP")
		(4 "In1.Cu" signal "L02_GND1")
		(6 "In2.Cu" signal "L03_SIG1")
		(8 "In3.Cu" signal "L04_GND2")
		(10 "In4.Cu" signal "L05_VCC1")
		(12 "In5.Cu" signal "L06_VCC2")
		(14 "In6.Cu" signal "L07_GND3")
		(16 "In7.Cu" signal "L08_SIG2")
		(18 "In8.Cu" signal "L09_GND4")
		(2 "B.Cu" signal "BOTTOM")
		(9 "F.Adhes" user "F.Adhesive")
		(11 "B.Adhes" user "B.Adhesive")
		(13 "F.Paste" user "Package Geometry/Pastemask Top")
		(15 "B.Paste" user "Package Geometry/Pastemask Bottom")
		(5 "F.SilkS" user "Ref Des/Silkscreen Top")
		(7 "B.SilkS" user "Ref Des/Silkscreen Bottom")
		(1 "F.Mask" user "Board Geometry/Soldermask Top")
		(3 "B.Mask" user "Board Geometry/Soldermask Bottom")
		(17 "Dwgs.User" user "User.Drawings")
		(19 "Cmts.User" user "User.Comments")
		(21 "Eco1.User" user "User.Eco1")
		(23 "Eco2.User" user "User.Eco2")
		(25 "Edge.Cuts" user "Board Geometry/Outline")
		(27 "Margin" user)
		(31 "F.CrtYd" user "Package Geometry/Place Bound Top")
		(29 "B.CrtYd" user "Package Geometry/Place Bound Bottom")
		(35 "F.Fab" user "Ref Des/Assembly Top")
		(33 "B.Fab" user "Ref Des/Assembly Bottom")
	)
	(footprint ""
		(layer "B.Cu")
		(at 138.811 -59.563 90)
		(property "Reference" "R247"
			(at 3.175 -0.03937 270)
			(unlocked yes)
			(layer "B.SilkS")
			(effects
				(font
					(size 0.7874 0.5842)
					(thickness 0.1524)
				)
				(justify mirror)
			)
		)
		(property "Value" "VAL*"
			(at -0.02032 2.13233 90)
			(unlocked yes)
			(layer "B.Fab")
			(hide yes)
			(effects
				(font
					(size 0.7874 0.5842)
					(thickness 0.1524)
				)
				(justify mirror)
			)
		)
		(property "Tolerance" "TOL*"
			(at -0.044704 3.05435 90)
			(unlocked yes)
			(layer "Cmts.User")
			(hide yes)
			(effects
				(font
					(size 0.7874 0.5842)
					(thickness 0.1524)
				)
				(justify mirror)
			)
		)
		(property "User Part Number" "PARTNUM*"
			(at -0.02032 4.024884 90)
			(unlocked yes)
			(layer "Cmts.User")
			(hide yes)
			(effects
				(font
					(size 0.7874 0.5842)
					(thickness 0.1524)
				)
				(justify mirror)
			)
		)
		(property "Device Type" "RESISTOR-G155-11002-01,10KOHM,A"
			(at -0.008382 1.210564 90)
			(unlocked yes)
			(layer "B.Fab")
			(hide yes)
			(effects
				(font
					(size 0.7874 0.5842)
					(thickness 0.1524)
				)
				(justify mirror)
			)
		)
		(duplicate_pad_numbers_are_jumpers no)
		(fp_line
			(start 1.143 -0.5588)
			(end 1.143 0.5588)
			(stroke
				(width 0.1)
				(type default)
			)
			(layer "B.SilkS")
		)
		(fp_line
			(start -1.143 -0.5588)
			(end 1.143 -0.5588)
			(stroke
				(width 0.1)
				(type default)
			)
			(layer "B.SilkS")
		)
		(fp_line
			(start 1.143 0.5588)
			(end -1.143 0.5588)
			(stroke
				(width 0.1)
				(type default)
			)
			(layer "B.SilkS")
		)
		(fp_line
			(start -1.143 0.5588)
			(end -1.143 -0.5588)
			(stroke
				(width 0.1)
				(type default)
			)
			(layer "B.SilkS")
		)
		(fp_poly
			(pts
				(xy 1.143 0.5588) (xy -1.143 0.5588) (xy -1.143 -0.5588) (xy 1.143 -0.5588)
			)
			(stroke
				(width 0)
				(type default)
			)
			(fill no)
			(layer "B.CrtYd")
		)
		(fp_line
			(start 0.508 -0.3048)
			(end 0.508 0.3048)
			(stroke
				(width 0.1)
				(type default)
			)
			(layer "B.Fab")
		)
		(fp_line
			(start -0.508 -0.3048)
			(end 0.508 -0.3048)
			(stroke
				(width 0.1)
				(type default)
			)
			(layer "B.Fab")
		)
		(fp_line
			(start 0.508 0.3048)
			(end -0.508 0.3048)
			(stroke
				(width 0.1)
				(type default)
			)
			(layer "B.Fab")
		)
		(fp_line
			(start -0.508 0.3048)
			(end -0.508 -0.3048)
			(stroke
				(width 0.1)
				(type default)
			)
			(layer "B.Fab")
		)
		(pad "1" smd rect
			(at 0.5334 0 270)
			(size 0.7112 0.6096)
			(layers "B.Cu" "B.Mask" "B.Paste")
			(net "VIN_XP1R0V")
		)
		(pad "2" smd rect
			(at -0.5334 0 270)
			(size 0.7112 0.6096)
			(layers "B.Cu" "B.Mask" "B.Paste")
			(net "UNNAMED_523_CAPACITOR_I7_1")
		)
		(zone
			(layer "B.Cu")
			(hatch none 0.5)
			(connect_pads
				(clearance 0)
			)
			(min_thickness 0.25)
			(keepout
				(tracks not_allowed)
				(vias allowed)
				(pads allowed)
				(copperpour not_allowed)
				(footprints allowed)
			)
			(placement
				(enabled no)
				(sheetname "")
			)
			(fill
				(thermal_gap 0.5)
				(thermal_bridge_width 0.5)
				(island_removal_mode 0)
			)
			(polygon
				(pts
					(xy 139.1158 -59.6392) (xy 138.5062 -59.6392) (xy 138.5062 -59.4868) (xy 139.1158 -59.4868)
				)
			)
		)
		(zone
			(layer "B.Cu")
			(hatch none 0.5)
			(connect_pads
				(clearance 0)
			)
			(min_thickness 0.25)
			(keepout
				(tracks allowed)
				(vias not_allowed)
				(pads allowed)
				(copperpour not_allowed)
				(footprints allowed)
			)
			(placement
				(enabled no)
				(sheetname "")
			)
			(fill
				(thermal_gap 0.5)
				(thermal_bridge_width 0.5)
				(island_removal_mode 0)
			)
			(polygon
				(pts
					(xy 139.1158 -59.6392) (xy 138.5062 -59.6392) (xy 138.5062 -59.4868) (xy 139.1158 -59.4868)
				)
			)
		)
	)
	(footprint ""
		(layer "B.Cu")
		(at 93.0148 -75.819 90)
		(property "Reference" "C180"
			(at 0.508 1.56083 270)
			(unlocked yes)
			(layer "B.SilkS")
			(effects
				(font
					(size 0.7874 0.5842)
					(thickness 0.1524)
				)
				(justify mirror)
			)
		)
		(property "Value" "VAL*"
			(at -0.0762 3.134106 90)
			(unlocked yes)
			(layer "B.Fab")
			(hide yes)
			(effects
				(font
					(size 0.7874 0.5842)
					(thickness 0.1524)
				)
				(justify mirror)
			)
		)
		(property "Tolerance" "TOL*"
			(at -0.0762 4.048506 90)
			(unlocked yes)
			(layer "Cmts.User")
			(hide yes)
			(effects
				(font
					(size 0.7874 0.5842)
					(thickness 0.1524)
				)
				(justify mirror)
			)
		)
		(property "User Part Number" "PARTNUM*"
			(at -0.1016 5.013706 90)
			(unlocked yes)
			(layer "Cmts.User")
			(hide yes)
			(effects
				(font
					(size 0.7874 0.5842)
					(thickness 0.1524)
				)
				(justify mirror)
			)
		)
		(property "Device Type" "CAPACITOR-G107-0F226-CM,22UF,2A"
			(at -0.0508 2.194306 90)
			(unlocked yes)
			(layer "B.Fab")
			(hide yes)
			(effects
				(font
					(size 0.7874 0.5842)
					(thickness 0.1524)
				)
				(justify mirror)
			)
		)
		(duplicate_pad_numbers_are_jumpers no)
		(fp_line
			(start 1.5748 -0.9398)
			(end 1.5748 0.9398)
			(stroke
				(width 0.1)
				(type default)
			)
			(layer "B.SilkS")
		)
		(fp_line
			(start -1.5748 -0.9398)
			(end 1.5748 -0.9398)
			(stroke
				(width 0.1)
				(type default)
			)
			(layer "B.SilkS")
		)
		(fp_line
			(start 1.5748 0.9398)
			(end -1.5748 0.9398)
			(stroke
				(width 0.1)
				(type default)
			)
			(layer "B.SilkS")
		)
		(fp_line
			(start -1.5748 0.9398)
			(end -1.5748 -0.9398)
			(stroke
				(width 0.1)
				(type default)
			)
			(layer "B.SilkS")
		)
		(fp_rect
			(start 1.5748 -0.9398)
			(end -1.5748 0.9398)
			(stroke
				(width 0)
				(type default)
			)
			(fill no)
			(layer "B.CrtYd")
		)
		(fp_line
			(start 1.016 -0.635)
			(end 1.016 0.635)
			(stroke
				(width 0.1)
				(type default)
			)
			(layer "B.Fab")
		)
		(fp_line
			(start -1.016 -0.635)
			(end 1.016 -0.635)
			(stroke
				(width 0.1)
				(type default)
			)
			(layer "B.Fab")
		)
		(fp_line
			(start 1.016 0.635)
			(end -1.016 0.635)
			(stroke
				(width 0.1)
				(type default)
			)
			(layer "B.Fab")
		)
		(fp_line
			(start -1.016 0.635)
			(end -1.016 -0.635)
			(stroke
				(width 0.1)
				(type default)
			)
			(layer "B.Fab")
		)
		(pad "1" smd rect
			(at 0.8382 0 270)
			(size 0.9652 1.3716)
			(layers "B.Cu" "B.Mask" "B.Paste")
			(net "XP3R3V")
		)
		(pad "2" smd rect
			(at -0.8382 0 270)
			(size 0.9652 1.3716)
			(layers "B.Cu" "B.Mask" "B.Paste")
			(net "SG")
		)
		(zone
			(layer "B.Cu")
			(hatch none 0.5)
			(connect_pads
				(clearance 0)
			)
			(min_thickness 0.25)
			(keepout
				(tracks allowed)
				(vias not_allowed)
				(pads allowed)
				(copperpour not_allowed)
				(footprints allowed)
			)
			(placement
				(enabled no)
				(sheetname "")
			)
			(fill
				(thermal_gap 0.5)
				(thermal_bridge_width 0.5)
				(island_removal_mode 0)
			)
			(polygon
				(pts
					(xy 92.3798 -76.0476) (xy 92.3798 -75.5904) (xy 93.6498 -75.5904) (xy 93.6498 -76.0476)
				)
			)
		)
	)
)
